#ISCELL
  mstr_misc dns *
  *
#ISCELL
  pure_quanta quanta_title_block_c *
  *
#CELL
  pure_quanta q_cap *
  page41_i1
#ISCELL
  logical_power universal_gnd *
  page41_i100
#CELL
  pure_quanta q_cap *
  page41_i101
#ISCELL
  logical_power universal_power *
  page41_i104
#CELL
  pure_quanta q_inductor *
  page41_i107
#CELL
  pure_quanta q_cap *
  page41_i108
#CELL
  pure_quanta q_cap *
  page41_i109
#ISCELL
  logical_power universal_power *
  page41_i11
#ISCELL
  logical_power universal_gnd *
  page41_i112
#ISCELL
  logical_power universal_power *
  page41_i114
#CELL
  pure_quanta q_cap *
  page41_i115
#CELL
  pure_quanta q_cap *
  page41_i116
#CELL
  pure_quanta q_cap *
  page41_i117
#CELL
  pure_quanta q_cap *
  page41_i118
#CELL
  pure_quanta q_cap *
  page41_i119
#CELL
  pure_quanta q_cap *
  page41_i122
#CELL
  pure_quanta q_cap *
  page41_i123
#CELL
  pure_quanta q_cap *
  page41_i124
#CELL
  pure_quanta q_cap *
  page41_i125
#CELL
  pure_quanta q_cap *
  page41_i126
#ISCELL
  logical_power universal_power *
  page41_i18
#ISCELL
  logical_power universal_gnd *
  page41_i24
#ISCELL
  logical_power universal_power *
  page41_i26
#ISCELL
  logical_power universal_power *
  page41_i27
#ISCELL
  logical_power universal_gnd *
  page41_i29
#ISCELL
  logical_power universal_power *
  page41_i35
#ISCELL
  logical_power universal_power *
  page41_i40
#ISCELL
  logical_power universal_gnd *
  page41_i42
#ISCELL
  logical_power universal_power *
  page41_i48
#ISCELL
  logical_power universal_power *
  page41_i53
#ISCELL
  logical_power universal_gnd *
  page41_i55
#ISCELL
  logical_power universal_power *
  page41_i6
#ISCELL
  logical_power universal_power *
  page41_i61
#ISCELL
  logical_power universal_power *
  page41_i66
#ISCELL
  logical_power universal_gnd *
  page41_i68
#ISCELL
  logical_power universal_gnd *
  page41_i7
#CELL
  pure_quanta q_res *
  page41_i71
#CELL
  pure_quanta q_res *
  page41_i72
#CELL
  pure_quanta q_res *
  page41_i73
#CELL
  pure_quanta q_res *
  page41_i74
#CELL
  pure_quanta q_res *
  page41_i75
#CELL
  pure_quanta q_res *
  page41_i76
#CELL
  pure_quanta q_cap *
  page41_i77
#CELL
  pure_quanta q_cap *
  page41_i78
#CELL
  pure_quanta q_cap *
  page41_i79
#CELL
  pure_quanta q_cap *
  page41_i8
#CELL
  pure_quanta q_cap *
  page41_i80
#CELL
  pure_quanta q_cap *
  page41_i81
#CELL
  pure_quanta q_cap *
  page41_i82
#CELL
  pure_quanta q_cap *
  page41_i83
#CELL
  pure_quanta q_cap *
  page41_i84
#CELL
  pure_quanta q_cap *
  page41_i85
#CELL
  pure_quanta q_cap *
  page41_i86
#CELL
  pure_quanta q_cap *
  page41_i87
#CELL
  pure_quanta q_cap *
  page41_i88
#CELL
  pure_quanta q_cap *
  page41_i89
#CELL
  pure_quanta q_cap *
  page41_i90
#CELL
  pure_quanta q_cap *
  page41_i91
#CELL
  pure_quanta q_cap *
  page41_i92
#CELL
  pure_quanta q_cap *
  page41_i93
#CELL
  pure_quanta q_cap *
  page41_i94
#CELL
  pure_quanta q_cap *
  page41_i95
#CELL
  pure_quanta q_cap *
  page41_i96
#ISCELL
  logical_power universal_power *
  page41_i97
#ISCELL
  logical_power universal_gnd *
  page41_i98
#CELL
  pure_quanta q_cap *
  page41_i99
